(kicad_pcb
	(version 20260206)
	(generator "pcbnew")
	(generator_version "10.0")
	(general
		(thickness 1.6)
		(legacy_teardrops no)
	)
	(paper "A4")
	(title_block
		(title "9052_F0T_PDB_Converter_Brick_F_V03_1208_1600_OCP.brd")
		(comment 1 "Grand Teton / footprints 156-160 of 578")
	)
	(layers
		(0 "F.Cu" signal "TOP")
		(4 "In1.Cu" signal "GND")
		(6 "In2.Cu" signal "IN1")
		(8 "In3.Cu" signal "GND1")
		(10 "In4.Cu" signal "VCC")
		(12 "In5.Cu" signal "VCC1")
		(14 "In6.Cu" signal "GND2")
		(16 "In7.Cu" signal "IN2")
		(18 "In8.Cu" signal "GND3")
		(2 "B.Cu" signal "BOTTOM")
		(9 "F.Adhes" user "F.Adhesive")
		(11 "B.Adhes" user "B.Adhesive")
		(13 "F.Paste" user "Package Geometry/Pastemask Top")
		(15 "B.Paste" user "Package Geometry/Pastemask Bottom")
		(5 "F.SilkS" user "Ref Des/Silkscreen Top")
		(7 "B.SilkS" user "Ref Des/Silkscreen Bottom")
		(1 "F.Mask" user "Board Geometry/Soldermask Top")
		(3 "B.Mask" user "Board Geometry/Soldermask Bottom")
		(17 "Dwgs.User" user "User.Drawings")
		(19 "Cmts.User" user "User.Comments")
		(21 "Eco1.User" user "User.Eco1")
		(23 "Eco2.User" user "User.Eco2")
		(25 "Edge.Cuts" user "Board Geometry/Outline")
		(27 "Margin" user)
		(31 "F.CrtYd" user "Package Geometry/Place Bound Top")
		(29 "B.CrtYd" user "Package Geometry/Place Bound Bottom")
		(35 "F.Fab" user "Ref Des/Assembly Top")
		(33 "B.Fab" user "Ref Des/Assembly Bottom")
	)
	(footprint ""
		(layer "F.Cu")
		(at 177.8 -12.0142)
		(property "Reference" "PU5"
			(at -1.397 -3.83413 0)
			(unlocked yes)
			(layer "F.SilkS")
			(effects
				(font
					(size 0.7874 0.5842)
					(thickness 0.1524)
				)
				(justify left)
			)
		)
		(property "Value" ""
			(at 0 0 0)
			(layer "F.Fab")
			(effects
				(font
					(size 1.27 1.27)
				)
			)
		)
		(duplicate_pad_numbers_are_jumpers no)
		(fp_line
			(start -1.050036 -1.549908)
			(end -0.503936 -1.549908)
			(stroke
				(width 0.1524)
				(type default)
			)
			(layer "F.SilkS")
		)
		(fp_line
			(start -1.050036 -1.253998)
			(end -1.050036 -1.549908)
			(stroke
				(width 0.1524)
				(type default)
			)
			(layer "F.SilkS")
		)
		(fp_line
			(start -1.050036 1.549908)
			(end -1.050036 1.253998)
			(stroke
				(width 0.1524)
				(type default)
			)
			(layer "F.SilkS")
		)
		(fp_line
			(start -0.503936 1.549908)
			(end -1.050036 1.549908)
			(stroke
				(width 0.1524)
				(type default)
			)
			(layer "F.SilkS")
		)
		(fp_line
			(start 0.503936 -1.549908)
			(end 1.050036 -1.549908)
			(stroke
				(width 0.1524)
				(type default)
			)
			(layer "F.SilkS")
		)
		(fp_line
			(start 1.050036 -1.549908)
			(end 1.050036 -1.253998)
			(stroke
				(width 0.1524)
				(type default)
			)
			(layer "F.SilkS")
		)
		(fp_line
			(start 1.050036 1.253998)
			(end 1.050036 1.549908)
			(stroke
				(width 0.1524)
				(type default)
			)
			(layer "F.SilkS")
		)
		(fp_line
			(start 1.050036 1.549908)
			(end 0.503936 1.549908)
			(stroke
				(width 0.1524)
				(type default)
			)
			(layer "F.SilkS")
		)
		(fp_poly
			(pts
				(xy -1.651 -0.847598) (xy -1.651 -1.152398) (xy -1.3462 -0.999998)
			)
			(stroke
				(width 0)
				(type default)
			)
			(fill yes)
			(layer "F.SilkS")
		)
		(fp_line
			(start -1.050036 -1.549908)
			(end 1.050036 -1.549908)
			(stroke
				(width 0.1)
				(type default)
			)
			(layer "F.Fab")
		)
		(fp_line
			(start -1.050036 1.549908)
			(end -1.050036 -1.549908)
			(stroke
				(width 0.1)
				(type default)
			)
			(layer "F.Fab")
		)
		(fp_line
			(start 1.050036 -1.549908)
			(end 1.050036 1.549908)
			(stroke
				(width 0.1)
				(type default)
			)
			(layer "F.Fab")
		)
		(fp_line
			(start 1.050036 1.549908)
			(end -1.050036 1.549908)
			(stroke
				(width 0.1)
				(type default)
			)
			(layer "F.Fab")
		)
		(fp_poly
			(pts
				(xy -2.2352 -0.618998) (xy -2.2352 -1.380998) (xy -1.4732 -0.999998)
			)
			(stroke
				(width 0)
				(type default)
			)
			(fill yes)
			(layer "F.Fab")
		)
		(pad "1" smd circle
			(at -0.94996 -0.999998 270)
			(size 0 0)
			(layers "F.Cu" "F.Mask" "F.Paste")
			(net "GND")
		)
		(pad "2" smd rect
			(at -0.849884 -0.499872 90)
			(size 0.254 0.9144)
			(layers "F.Cu" "F.Mask" "F.Paste")
			(net "SW_P3V3_AUX_PH")
		)
		(pad "3" smd rect
			(at -0.649986 0 90)
			(size 0.254 1.3208)
			(layers "F.Cu" "F.Mask" "F.Paste")
			(net "SW_P12V_FILT__P3V3_AUX")
		)
		(pad "4" smd rect
			(at -0.849884 0.499872 90)
			(size 0.254 0.9144)
			(layers "F.Cu" "F.Mask" "F.Paste")
			(net "P3V3_AUX_CS")
		)
		(pad "5" smd circle
			(at -0.94996 0.999998 270)
			(size 0 0)
			(layers "F.Cu" "F.Mask" "F.Paste")
			(net "P12V_BRICK0_PWRGD")
		)
		(pad "6" smd circle
			(at -0.249936 1.450086)
			(size 0 0)
			(layers "F.Cu" "F.Mask" "F.Paste")
			(net "P3V3_AUX_FB")
		)
		(pad "7" smd circle
			(at 0.249936 1.450086)
			(size 0 0)
			(layers "F.Cu" "F.Mask" "F.Paste")
			(net "GND")
		)
		(pad "8" smd circle
			(at 0.94996 0.999998 90)
			(size 0 0)
			(layers "F.Cu" "F.Mask" "F.Paste")
			(net "P3V3_AUX_REF")
		)
		(pad "9" smd rect
			(at 0.849884 0.499872 90)
			(size 0.254 0.9144)
			(layers "F.Cu" "F.Mask" "F.Paste")
			(net "P3V3_AUX_PWRGD")
		)
		(pad "10" smd rect
			(at 0.849884 0 90)
			(size 0.254 0.9144)
			(layers "F.Cu" "F.Mask" "F.Paste")
			(net "SW_P3V3_AUX_BT")
		)
		(pad "11" smd rect
			(at 0.849884 -0.499872 90)
			(size 0.254 0.9144)
			(layers "F.Cu" "F.Mask" "F.Paste")
			(net "SW_P3V3_AUX_PH")
		)
		(pad "12" smd circle
			(at 0.94996 -0.999998 90)
			(size 0 0)
			(layers "F.Cu" "F.Mask" "F.Paste")
			(net "P3V3_AUX_MODE")
		)
		(pad "13" smd circle
			(at 0.249936 -1.450086 180)
			(size 0 0)
			(layers "F.Cu" "F.Mask" "F.Paste")
			(net "P3V3_AUX_VCC")
		)
		(pad "14" smd circle
			(at -0.249936 -1.450086 180)
			(size 0 0)
			(layers "F.Cu" "F.Mask" "F.Paste")
			(net "GND")
		)
	)
	(footprint ""
		(layer "F.Cu")
		(at 296.164 -36.703 -90)
		(property "Reference" "R5886"
			(at 0 0 270)
			(layer "F.SilkS")
			(hide yes)
			(effects
				(font
					(size 1.27 1.27)
				)
			)
		)
		(property "Value" ""
			(at 0 0 270)
			(layer "F.Fab")
			(effects
				(font
					(size 1.27 1.27)
				)
			)
		)
		(duplicate_pad_numbers_are_jumpers no)
		(fp_line
			(start -1.651 0.8382)
			(end -1.651 -0.8382)
			(stroke
				(width 0.1524)
				(type default)
			)
			(layer "F.SilkS")
		)
		(fp_line
			(start 1.651 0.8382)
			(end -1.651 0.8382)
			(stroke
				(width 0.1524)
				(type default)
			)
			(layer "F.SilkS")
		)
		(fp_line
			(start -1.651 -0.8382)
			(end 1.651 -0.8382)
			(stroke
				(width 0.1524)
				(type default)
			)
			(layer "F.SilkS")
		)
		(fp_line
			(start 1.651 -0.8382)
			(end 1.651 0.8382)
			(stroke
				(width 0.1524)
				(type default)
			)
			(layer "F.SilkS")
		)
		(fp_line
			(start -1.559814 0.7366)
			(end -1.524 0.7366)
			(stroke
				(width 0.1)
				(type default)
			)
			(layer "F.Fab")
		)
		(fp_line
			(start -1.524 0.7366)
			(end 1.524 0.7366)
			(stroke
				(width 0.1)
				(type default)
			)
			(layer "F.Fab")
		)
		(fp_line
			(start 1.524 0.7366)
			(end 1.560576 0.7366)
			(stroke
				(width 0.1)
				(type default)
			)
			(layer "F.Fab")
		)
		(fp_line
			(start 1.560576 0.7366)
			(end 1.560576 -0.7366)
			(stroke
				(width 0.1)
				(type default)
			)
			(layer "F.Fab")
		)
		(fp_line
			(start -1.559814 -0.7366)
			(end -1.559814 0.7366)
			(stroke
				(width 0.1)
				(type default)
			)
			(layer "F.Fab")
		)
		(fp_line
			(start -1.524 -0.7366)
			(end -1.559814 -0.7366)
			(stroke
				(width 0.1)
				(type default)
			)
			(layer "F.Fab")
		)
		(fp_line
			(start 1.524 -0.7366)
			(end -1.524 -0.7366)
			(stroke
				(width 0.1)
				(type default)
			)
			(layer "F.Fab")
		)
		(fp_line
			(start 1.560576 -0.7366)
			(end 1.524 -0.7366)
			(stroke
				(width 0.1)
				(type default)
			)
			(layer "F.Fab")
		)
		(pad "1" smd rect
			(at -0.94996 0 90)
			(size 1.1176 1.3716)
			(layers "F.Cu" "F.Mask" "F.Paste")
			(net "P52V_1_FUSE_1")
		)
		(pad "2" smd rect
			(at 0.94996 0 90)
			(size 1.1176 1.3716)
			(layers "F.Cu" "F.Mask" "F.Paste")
			(net "FM_HSC_EN_FUSE")
		)
	)
	(footprint ""
		(layer "F.Cu")
		(at 209.931 -87.757 180)
		(property "Reference" "R62"
			(at 0 0 180)
			(layer "F.SilkS")
			(hide yes)
			(effects
				(font
					(size 1.27 1.27)
				)
			)
		)
		(property "Value" ""
			(at 0 0 180)
			(layer "F.Fab")
			(effects
				(font
					(size 1.27 1.27)
				)
			)
		)
		(duplicate_pad_numbers_are_jumpers no)
		(fp_line
			(start 2.234946 0.9271)
			(end -2.234946 0.9271)
			(stroke
				(width 0.1524)
				(type default)
			)
			(layer "F.SilkS")
		)
		(fp_line
			(start 2.234946 -0.9271)
			(end 2.234946 0.9271)
			(stroke
				(width 0.1524)
				(type default)
			)
			(layer "F.SilkS")
		)
		(fp_line
			(start -2.234946 0.9271)
			(end -2.234946 -0.9271)
			(stroke
				(width 0.1524)
				(type default)
			)
			(layer "F.SilkS")
		)
		(fp_line
			(start -2.234946 -0.9271)
			(end 2.234946 -0.9271)
			(stroke
				(width 0.1524)
				(type default)
			)
			(layer "F.SilkS")
		)
		(fp_line
			(start 1.575054 0.824992)
			(end 1.575054 -0.824992)
			(stroke
				(width 0.1)
				(type default)
			)
			(layer "F.Fab")
		)
		(fp_line
			(start 1.575054 -0.824992)
			(end -1.575054 -0.824992)
			(stroke
				(width 0.1)
				(type default)
			)
			(layer "F.Fab")
		)
		(fp_line
			(start -1.575054 0.824992)
			(end 1.575054 0.824992)
			(stroke
				(width 0.1)
				(type default)
			)
			(layer "F.Fab")
		)
		(fp_line
			(start -1.575054 -0.824992)
			(end -1.575054 0.824992)
			(stroke
				(width 0.1)
				(type default)
			)
			(layer "F.Fab")
		)
		(pad "1" smd rect
			(at -1.599946 0 180)
			(size 1.016 1.6002)
			(layers "F.Cu" "F.Mask" "F.Paste")
			(net "LED_D1_R3")
		)
		(pad "2" smd rect
			(at 1.599946 0 180)
			(size 1.016 1.6002)
			(layers "F.Cu" "F.Mask" "F.Paste")
			(net "LED_D1_R4")
		)
	)
	(footprint ""
		(layer "F.Cu")
		(at 179.065174 -61.849)
		(property "Reference" "PC123"
			(at 0 0 0)
			(layer "F.SilkS")
			(hide yes)
			(effects
				(font
					(size 1.27 1.27)
				)
			)
		)
		(property "Value" ""
			(at 0 0 0)
			(layer "F.Fab")
			(effects
				(font
					(size 1.27 1.27)
				)
			)
		)
		(duplicate_pad_numbers_are_jumpers no)
		(fp_line
			(start -0.7874 -0.4064)
			(end 0.7874 -0.4064)
			(stroke
				(width 0.1524)
				(type default)
			)
			(layer "F.SilkS")
		)
		(fp_line
			(start -0.7874 0.4064)
			(end -0.7874 -0.4064)
			(stroke
				(width 0.1524)
				(type default)
			)
			(layer "F.SilkS")
		)
		(fp_line
			(start 0.7874 -0.4064)
			(end 0.7874 0.4064)
			(stroke
				(width 0.1524)
				(type default)
			)
			(layer "F.SilkS")
		)
		(fp_line
			(start 0.7874 0.4064)
			(end -0.7874 0.4064)
			(stroke
				(width 0.1524)
				(type default)
			)
			(layer "F.SilkS")
		)
		(fp_line
			(start -0.6858 -0.3048)
			(end -0.1016 -0.3048)
			(stroke
				(width 0.1)
				(type default)
			)
			(layer "F.Fab")
		)
		(fp_line
			(start -0.6858 0.3048)
			(end -0.6858 -0.3048)
			(stroke
				(width 0.1)
				(type default)
			)
			(layer "F.Fab")
		)
		(fp_line
			(start -0.1016 -0.3048)
			(end -0.1016 -0.2794)
			(stroke
				(width 0.1)
				(type default)
			)
			(layer "F.Fab")
		)
		(fp_line
			(start -0.1016 -0.2794)
			(end 0.1016 -0.2794)
			(stroke
				(width 0.1)
				(type default)
			)
			(layer "F.Fab")
		)
		(fp_line
			(start -0.1016 0.2794)
			(end -0.1016 0.3048)
			(stroke
				(width 0.1)
				(type default)
			)
			(layer "F.Fab")
		)
		(fp_line
			(start -0.1016 0.3048)
			(end -0.6858 0.3048)
			(stroke
				(width 0.1)
				(type default)
			)
			(layer "F.Fab")
		)
		(fp_line
			(start 0.1016 -0.3048)
			(end 0.6858 -0.3048)
			(stroke
				(width 0.1)
				(type default)
			)
			(layer "F.Fab")
		)
		(fp_line
			(start 0.1016 -0.2794)
			(end 0.1016 -0.3048)
			(stroke
				(width 0.1)
				(type default)
			)
			(layer "F.Fab")
		)
		(fp_line
			(start 0.1016 0.2794)
			(end -0.1016 0.2794)
			(stroke
				(width 0.1)
				(type default)
			)
			(layer "F.Fab")
		)
		(fp_line
			(start 0.1016 0.3048)
			(end 0.1016 0.2794)
			(stroke
				(width 0.1)
				(type default)
			)
			(layer "F.Fab")
		)
		(fp_line
			(start 0.6858 -0.3048)
			(end 0.6858 0.3048)
			(stroke
				(width 0.1)
				(type default)
			)
			(layer "F.Fab")
		)
		(fp_line
			(start 0.6858 0.3048)
			(end 0.1016 0.3048)
			(stroke
				(width 0.1)
				(type default)
			)
			(layer "F.Fab")
		)
		(pad "1" smd rect
			(at -0.40005 0 180)
			(size 0.4572 0.508)
			(layers "F.Cu" "F.Mask" "F.Paste")
			(net "P12V_BRICK")
		)
		(pad "2" smd rect
			(at 0.40005 0 180)
			(size 0.4572 0.508)
			(layers "F.Cu" "F.Mask" "F.Paste")
			(net "GND")
		)
	)
	(footprint ""
		(layer "F.Cu")
		(at 280.39568 -126.477268)
		(property "Reference" "PQ1"
			(at -7.72668 -5.703062 0)
			(unlocked yes)
			(layer "F.SilkS")
			(effects
				(font
					(size 0.7874 0.5842)
					(thickness 0.1524)
				)
				(justify left)
			)
		)
		(property "Value" ""
			(at 0 0 0)
			(layer "F.Fab")
			(effects
				(font
					(size 1.27 1.27)
				)
			)
		)
		(duplicate_pad_numbers_are_jumpers no)
		(fp_line
			(start -7.649972 -4.99999)
			(end -7.649972 -3.3274)
			(stroke
				(width 0.1524)
				(type default)
			)
			(layer "F.SilkS")
		)
		(fp_line
			(start -7.649972 -1.7526)
			(end -7.649972 1.7526)
			(stroke
				(width 0.1524)
				(type default)
			)
			(layer "F.SilkS")
		)
		(fp_line
			(start -7.649972 3.3274)
			(end -7.649972 4.99999)
			(stroke
				(width 0.1524)
				(type default)
			)
			(layer "F.SilkS")
		)
		(fp_line
			(start -7.649972 4.99999)
			(end 5.115814 4.99999)
			(stroke
				(width 0.1524)
				(type default)
			)
			(layer "F.SilkS")
		)
		(fp_line
			(start 5.115814 -4.99999)
			(end -7.649972 -4.99999)
			(stroke
				(width 0.1524)
				(type default)
			)
			(layer "F.SilkS")
		)
		(fp_line
			(start 7.630414 4.99999)
			(end 7.649972 4.99999)
			(stroke
				(width 0.1524)
				(type default)
			)
			(layer "F.SilkS")
		)
		(fp_line
			(start 7.649972 -4.99999)
			(end 7.630414 -4.99999)
			(stroke
				(width 0.1524)
				(type default)
			)
			(layer "F.SilkS")
		)
		(fp_line
			(start 7.649972 4.99999)
			(end 7.649972 -4.99999)
			(stroke
				(width 0.1524)
				(type default)
			)
			(layer "F.SilkS")
		)
		(fp_line
			(start -7.649972 -4.99999)
			(end -7.649972 4.99999)
			(stroke
				(width 0.1)
				(type default)
			)
			(layer "F.Fab")
		)
		(fp_line
			(start -7.649972 4.99999)
			(end 7.649972 4.99999)
			(stroke
				(width 0.1)
				(type default)
			)
			(layer "F.Fab")
		)
		(fp_line
			(start 7.649972 -4.99999)
			(end -7.649972 -4.99999)
			(stroke
				(width 0.1)
				(type default)
			)
			(layer "F.Fab")
		)
		(fp_line
			(start 7.649972 4.99999)
			(end 7.649972 -4.99999)
			(stroke
				(width 0.1)
				(type default)
			)
			(layer "F.Fab")
		)
		(pad "D" smd circle
			(at 2.15011 0)
			(size 0 0)
			(layers "F.Cu" "F.Mask" "F.Paste")
			(net "P52V_HS1_DRAIN_1")
		)
		(pad "G" smd rect
			(at -7.050024 -2.54 270)
			(size 1.3208 3.0988)
			(layers "F.Cu" "F.Mask" "F.Paste")
			(net "P52V_HS1_GATE1")
		)
		(pad "S" smd rect
			(at -7.050024 2.54 270)
			(size 1.3208 3.0988)
			(layers "F.Cu" "F.Mask" "F.Paste")
			(net "P52V_HS")
		)
		(zone
			(layer "F.Cu")
			(hatch none 0.5)
			(connect_pads
				(clearance 0)
			)
			(min_thickness 0.25)
			(keepout
				(tracks not_allowed)
				(vias allowed)
				(pads allowed)
				(copperpour not_allowed)
				(footprints allowed)
			)
			(placement
				(enabled no)
				(sheetname "")
			)
			(fill
				(thermal_gap 0.5)
				(thermal_bridge_width 0.5)
				(island_removal_mode 0)
			)
			(polygon
				(pts
					(xy 285.57728 -131.455668) (xy 272.75028 -131.455668) (xy 272.75028 -129.728468) (xy 274.96008 -129.728468)
					(xy 274.96008 -128.306068) (xy 272.75028 -128.306068) (xy 272.75028 -124.648468) (xy 274.96008 -124.648468)
					(xy 274.96008 -123.226068) (xy 272.75028 -123.226068) (xy 272.75028 -121.498868) (xy 285.57728 -121.498868)
					(xy 285.57728 -122.667268) (xy 279.37968 -122.667268) (xy 279.37968 -130.287268) (xy 285.57728 -130.287268)
				)
			)
		)
	)
)
